# S9S_MB_2U (Grand Teton) — schematic netlist excerpt (pin names and nets, part order shuffled) for the footprints in the layout excerpt that follows; sources: Cadence DE-HDL packaged netlist, KiCad conversion of 03242023_DA0F0TMBIJ0_F0T_Motherboard_J_brd_V01_OCP.brd

PC497_P1_8  Q_CAP  22UF 4V 20% X6S  pkg C0805  page 288 : A = PVCCIN_CPU1 ; B = GND
C210  Q_CAP  0.1UF 25V 10% X7R  pkg 0402  page 206 : A = P3V3_DB2000_VDDR ; B = GND
R1944  Q_RES  0 5% CHIP  pkg 0402LF  page 215 : A = IRQ_PCH_SCI_WHEA_R_N ; B = IRQ_PCH_SCI_WHEA_N

(kicad_pcb
	(version 20260206)
	(generator "pcbnew")
	(generator_version "10.0")
	(general
		(thickness 1.6)
		(legacy_teardrops no)
	)
	(paper "A4")
	(title_block
		(title "03242023_DA0F0TMBIJ0_F0T_Motherboard_J_brd_V01_OCP.brd")
		(comment 1 "Grand Teton / footprints 5269-5271 of 6105")
	)
	(layers
		(0 "F.Cu" signal "TOP")
		(4 "In1.Cu" signal "GND")
		(6 "In2.Cu" signal "IN1")
		(8 "In3.Cu" signal "GND1")
		(10 "In4.Cu" signal "IN2")
		(12 "In5.Cu" signal "GND2")
		(14 "In6.Cu" signal "IN3")
		(16 "In7.Cu" signal "GND3")
		(18 "In8.Cu" signal "VCC")
		(20 "In9.Cu" signal "VCC1")
		(22 "In10.Cu" signal "GND4")
		(24 "In11.Cu" signal "IN4")
		(26 "In12.Cu" signal "GND5")
		(28 "In13.Cu" signal "IN5")
		(30 "In14.Cu" signal "GND6")
		(32 "In15.Cu" signal "IN6")
		(34 "In16.Cu" signal "GND7")
		(2 "B.Cu" signal "BOTTOM")
		(9 "F.Adhes" user "F.Adhesive")
		(11 "B.Adhes" user "B.Adhesive")
		(13 "F.Paste" user "Package Geometry/Pastemask Top")
		(15 "B.Paste" user "Package Geometry/Pastemask Bottom")
		(5 "F.SilkS" user "Ref Des/Silkscreen Top")
		(7 "B.SilkS" user "Ref Des/Silkscreen Bottom")
		(1 "F.Mask" user "Board Geometry/Soldermask Top")
		(3 "B.Mask" user "Board Geometry/Soldermask Bottom")
		(17 "Dwgs.User" user "User.Drawings")
		(19 "Cmts.User" user "User.Comments")
		(21 "Eco1.User" user "User.Eco1")
		(23 "Eco2.User" user "User.Eco2")
		(25 "Edge.Cuts" user "Board Geometry/Outline")
		(27 "Margin" user)
		(31 "F.CrtYd" user "Package Geometry/Place Bound Top")
		(29 "B.CrtYd" user "Package Geometry/Place Bound Bottom")
		(35 "F.Fab" user "Ref Des/Assembly Top")
		(33 "B.Fab" user "Ref Des/Assembly Bottom")
	)
	(footprint ""
		(layer "B.Cu")
		(at 312.93054 -48.890428 180)
		(property "Reference" "R1944"
			(at 0 0 0)
			(layer "B.SilkS")
			(hide yes)
			(effects
				(font
					(size 1.27 1.27)
				)
				(justify mirror)
			)
		)
		(property "Value" ""
			(at 0 0 0)
			(layer "B.Fab")
			(effects
				(font
					(size 1.27 1.27)
				)
				(justify mirror)
			)
		)
		(duplicate_pad_numbers_are_jumpers no)
		(fp_line
			(start 0.7874 0.4064)
			(end 0.7874 -0.4064)
			(stroke
				(width 0.1524)
				(type default)
			)
			(layer "B.SilkS")
		)
		(fp_line
			(start 0.7874 -0.4064)
			(end -0.7874 -0.4064)
			(stroke
				(width 0.1524)
				(type default)
			)
			(layer "B.SilkS")
		)
		(fp_line
			(start -0.7874 0.4064)
			(end 0.7874 0.4064)
			(stroke
				(width 0.1524)
				(type default)
			)
			(layer "B.SilkS")
		)
		(fp_line
			(start -0.7874 -0.4064)
			(end -0.7874 0.4064)
			(stroke
				(width 0.1524)
				(type default)
			)
			(layer "B.SilkS")
		)
		(fp_line
			(start 0.67945 0.3048)
			(end 0.67945 -0.305054)
			(stroke
				(width 0.1)
				(type default)
			)
			(layer "B.Fab")
		)
		(fp_line
			(start 0.67945 -0.305054)
			(end 0.12065 -0.305054)
			(stroke
				(width 0.1)
				(type default)
			)
			(layer "B.Fab")
		)
		(fp_line
			(start 0.12065 0.3048)
			(end 0.67945 0.3048)
			(stroke
				(width 0.1)
				(type default)
			)
			(layer "B.Fab")
		)
		(fp_line
			(start 0.12065 0.2794)
			(end 0.12065 0.3048)
			(stroke
				(width 0.1)
				(type default)
			)
			(layer "B.Fab")
		)
		(fp_line
			(start 0.12065 -0.2794)
			(end -0.12065 -0.2794)
			(stroke
				(width 0.1)
				(type default)
			)
			(layer "B.Fab")
		)
		(fp_line
			(start 0.12065 -0.305054)
			(end 0.12065 -0.2794)
			(stroke
				(width 0.1)
				(type default)
			)
			(layer "B.Fab")
		)
		(fp_line
			(start -0.120396 0.3048)
			(end -0.120396 0.2794)
			(stroke
				(width 0.1)
				(type default)
			)
			(layer "B.Fab")
		)
		(fp_line
			(start -0.120396 0.2794)
			(end 0.12065 0.2794)
			(stroke
				(width 0.1)
				(type default)
			)
			(layer "B.Fab")
		)
		(fp_line
			(start -0.12065 -0.2794)
			(end -0.12065 -0.3048)
			(stroke
				(width 0.1)
				(type default)
			)
			(layer "B.Fab")
		)
		(fp_line
			(start -0.12065 -0.3048)
			(end -0.67945 -0.3048)
			(stroke
				(width 0.1)
				(type default)
			)
			(layer "B.Fab")
		)
		(fp_line
			(start -0.67945 0.3048)
			(end -0.120396 0.3048)
			(stroke
				(width 0.1)
				(type default)
			)
			(layer "B.Fab")
		)
		(fp_line
			(start -0.67945 -0.3048)
			(end -0.67945 0.3048)
			(stroke
				(width 0.1)
				(type default)
			)
			(layer "B.Fab")
		)
		(pad "1" smd circle
			(at 0.40005 0)
			(size 0 0)
			(layers "B.Cu" "B.Mask" "B.Paste")
			(net "IRQ_PCH_SCI_WHEA_R_N")
		)
		(pad "2" smd circle
			(at -0.40005 0)
			(size 0 0)
			(layers "B.Cu" "B.Mask" "B.Paste")
			(net "IRQ_PCH_SCI_WHEA_N")
		)
	)
	(footprint ""
		(layer "B.Cu")
		(at 136.417558 -333.62138 -90)
		(property "Reference" "PC497_P1_8"
			(at 0 0 90)
			(layer "B.SilkS")
			(hide yes)
			(effects
				(font
					(size 1.27 1.27)
				)
				(justify mirror)
			)
		)
		(property "Value" ""
			(at 0 0 90)
			(layer "B.Fab")
			(effects
				(font
					(size 1.27 1.27)
				)
				(justify mirror)
			)
		)
		(duplicate_pad_numbers_are_jumpers no)
		(fp_line
			(start -1.524 0.762)
			(end 1.524 0.762)
			(stroke
				(width 0.1524)
				(type default)
			)
			(layer "B.SilkS")
		)
		(fp_line
			(start 1.524 0.762)
			(end 1.524 -0.762)
			(stroke
				(width 0.1524)
				(type default)
			)
			(layer "B.SilkS")
		)
		(fp_line
			(start -1.524 -0.762)
			(end -1.524 0.762)
			(stroke
				(width 0.1524)
				(type default)
			)
			(layer "B.SilkS")
		)
		(fp_line
			(start 1.524 -0.762)
			(end -1.524 -0.762)
			(stroke
				(width 0.1524)
				(type default)
			)
			(layer "B.SilkS")
		)
		(fp_line
			(start -1.1049 0.724916)
			(end -1.1049 -0.724916)
			(stroke
				(width 0.1)
				(type default)
			)
			(layer "B.Fab")
		)
		(fp_line
			(start 1.1049 0.724916)
			(end -1.1049 0.724916)
			(stroke
				(width 0.1)
				(type default)
			)
			(layer "B.Fab")
		)
		(fp_line
			(start -1.1049 -0.724916)
			(end 1.1049 -0.724916)
			(stroke
				(width 0.1)
				(type default)
			)
			(layer "B.Fab")
		)
		(fp_line
			(start 1.1049 -0.724916)
			(end 1.1049 0.724916)
			(stroke
				(width 0.1)
				(type default)
			)
			(layer "B.Fab")
		)
		(pad "1" smd rect
			(at 0.889 0 270)
			(size 1.016 1.27)
			(layers "B.Cu" "B.Mask" "B.Paste")
			(net "PVCCIN_CPU1")
		)
		(pad "2" smd rect
			(at -0.889 0 270)
			(size 1.016 1.27)
			(layers "B.Cu" "B.Mask" "B.Paste")
			(net "GND")
		)
	)
	(footprint ""
		(layer "B.Cu")
		(at 237.836202 -127.48895 180)
		(property "Reference" "C210"
			(at 0 0 0)
			(layer "B.SilkS")
			(hide yes)
			(effects
				(font
					(size 1.27 1.27)
				)
				(justify mirror)
			)
		)
		(property "Value" ""
			(at 0 0 0)
			(layer "B.Fab")
			(effects
				(font
					(size 1.27 1.27)
				)
				(justify mirror)
			)
		)
		(duplicate_pad_numbers_are_jumpers no)
		(fp_line
			(start 0.7874 0.4064)
			(end 0.7874 -0.4064)
			(stroke
				(width 0.1524)
				(type default)
			)
			(layer "B.SilkS")
		)
		(fp_line
			(start 0.7874 -0.4064)
			(end -0.7874 -0.4064)
			(stroke
				(width 0.1524)
				(type default)
			)
			(layer "B.SilkS")
		)
		(fp_line
			(start -0.7874 0.4064)
			(end 0.7874 0.4064)
			(stroke
				(width 0.1524)
				(type default)
			)
			(layer "B.SilkS")
		)
		(fp_line
			(start -0.7874 -0.4064)
			(end -0.7874 0.4064)
			(stroke
				(width 0.1524)
				(type default)
			)
			(layer "B.SilkS")
		)
		(fp_line
			(start 0.67945 0.3048)
			(end 0.67945 -0.305054)
			(stroke
				(width 0.1)
				(type default)
			)
			(layer "B.Fab")
		)
		(fp_line
			(start 0.67945 -0.305054)
			(end 0.12065 -0.305054)
			(stroke
				(width 0.1)
				(type default)
			)
			(layer "B.Fab")
		)
		(fp_line
			(start 0.12065 0.3048)
			(end 0.67945 0.3048)
			(stroke
				(width 0.1)
				(type default)
			)
			(layer "B.Fab")
		)
		(fp_line
			(start 0.12065 0.2794)
			(end 0.12065 0.3048)
			(stroke
				(width 0.1)
				(type default)
			)
			(layer "B.Fab")
		)
		(fp_line
			(start 0.12065 -0.2794)
			(end -0.12065 -0.2794)
			(stroke
				(width 0.1)
				(type default)
			)
			(layer "B.Fab")
		)
		(fp_line
			(start 0.12065 -0.305054)
			(end 0.12065 -0.2794)
			(stroke
				(width 0.1)
				(type default)
			)
			(layer "B.Fab")
		)
		(fp_line
			(start -0.120396 0.3048)
			(end -0.120396 0.2794)
			(stroke
				(width 0.1)
				(type default)
			)
			(layer "B.Fab")
		)
		(fp_line
			(start -0.120396 0.2794)
			(end 0.12065 0.2794)
			(stroke
				(width 0.1)
				(type default)
			)
			(layer "B.Fab")
		)
		(fp_line
			(start -0.12065 -0.2794)
			(end -0.12065 -0.3048)
			(stroke
				(width 0.1)
				(type default)
			)
			(layer "B.Fab")
		)
		(fp_line
			(start -0.12065 -0.3048)
			(end -0.67945 -0.3048)
			(stroke
				(width 0.1)
				(type default)
			)
			(layer "B.Fab")
		)
		(fp_line
			(start -0.67945 0.3048)
			(end -0.120396 0.3048)
			(stroke
				(width 0.1)
				(type default)
			)
			(layer "B.Fab")
		)
		(fp_line
			(start -0.67945 -0.3048)
			(end -0.67945 0.3048)
			(stroke
				(width 0.1)
				(type default)
			)
			(layer "B.Fab")
		)
		(pad "1" smd circle
			(at 0.40005 0)
			(size 0 0)
			(layers "B.Cu" "B.Mask" "B.Paste")
			(net "P3V3_DB2000_VDDR")
		)
		(pad "2" smd circle
			(at -0.40005 0)
			(size 0 0)
			(layers "B.Cu" "B.Mask" "B.Paste")
			(net "GND")
		)
	)
)
